(kicad_pcb
	(version 20241229)
	(generator "pcbnew")
	(generator_version "9.0")
	(general
		(thickness 1.62)
		(legacy_teardrops no)
	)
	(paper "A3")
	(title_block
		(title "COM Express 7 Baseboard")
		(date "2025-02-04")
		(rev "1.1.2")
		(company "Antmicro Ltd")
		(comment 1 "www.antmicro.com")
		(comment 9 "footprint 546 of 802 (J5), pads 43-71 of 71")
	)
	(layers
		(0 "F.Cu" signal)
		(4 "In1.Cu" signal)
		(6 "In2.Cu" signal)
		(8 "In3.Cu" signal)
		(10 "In4.Cu" signal)
		(12 "In5.Cu" signal)
		(14 "In6.Cu" signal)
		(2 "B.Cu" signal)
		(9 "F.Adhes" user "F.Adhesive")
		(11 "B.Adhes" user "B.Adhesive")
		(13 "F.Paste" user)
		(15 "B.Paste" user)
		(5 "F.SilkS" user "F.Silkscreen")
		(7 "B.SilkS" user "B.Silkscreen")
		(1 "F.Mask" user)
		(3 "B.Mask" user)
		(17 "Dwgs.User" user "User.Drawings")
		(19 "Cmts.User" user "User.Comments")
		(21 "Eco1.User" user "User.Eco1")
		(23 "Eco2.User" user "User.Eco2")
		(25 "Edge.Cuts" user)
		(27 "Margin" user)
		(31 "F.CrtYd" user "F.Courtyard")
		(29 "B.CrtYd" user "B.Courtyard")
		(35 "F.Fab" user)
		(33 "B.Fab" user)
	)
	(footprint "antmicro-footprints:Bus_M.2_Socket_Key_M_Amphenol_MDT180M03001"
		(layer "B.Cu")
		(at 180.15 102.11 -90)
		(property "Reference" "J5"
			(at -12.26 5 90)
			(layer "B.SilkS")
			(effects
				(font
					(size 0.7 0.7)
					(thickness 0.15)
				)
				(justify left bottom mirror)
			)
		)
		(property "Value" "Bus_M.2_MDT180M03001"
			(at 0 -6.3 90)
			(layer "B.Fab")
			(hide yes)
			(effects
				(font
					(size 0.7 0.7)
					(thickness 0.15)
				)
				(justify left bottom mirror)
			)
		)
		(property "Datasheet" "https://cdn.amphenol-cs.com/media/wysiwyg/files/drawing/mdt180xxx001.pdf"
			(at 0 0 90)
			(layer "B.Fab")
			(hide yes)
			(effects
				(font
					(size 1.27 1.27)
					(thickness 0.15)
				)
				(justify mirror)
			)
		)
		(property "Manufacturer" "Amphenol"
			(at 0 0 270)
			(unlocked yes)
			(layer "B.Fab")
			(hide yes)
			(effects
				(font
					(size 1 1)
					(thickness 0.15)
				)
				(justify mirror)
			)
		)
		(property "MPN" "MDT180M03001"
			(at 0 0 270)
			(unlocked yes)
			(layer "B.Fab")
			(hide yes)
			(effects
				(font
					(size 1 1)
					(thickness 0.15)
				)
				(justify mirror)
			)
		)
		(property "Author" "Antmicro"
			(at 0 0 270)
			(unlocked yes)
			(layer "B.Fab")
			(hide yes)
			(effects
				(font
					(size 1 1)
					(thickness 0.15)
				)
				(justify mirror)
			)
		)
		(property "License" "Apache-2.0"
			(at 0 0 270)
			(unlocked yes)
			(layer "B.Fab")
			(hide yes)
			(effects
				(font
					(size 1 1)
					(thickness 0.15)
				)
				(justify mirror)
			)
		)
		(sheetname "M.2 key M #1")
		(sheetfile "m2keym_low.kicad_sch")
		(attr smd)
		(pad "41" smd rect
			(at 0.75 3.95 270)
			(size 0.3 1.5)
			(layers "B.Cu" "B.Mask" "B.Paste")
			(net 264 "/Com Express 7 Interfaces/PCIe_{B2Bx4}.RX0+")
			(pinfunction "PER0_N")
			(pintype "output")
			(teardrops
				(best_length_ratio 0.2)
				(max_length 1)
				(best_width_ratio 0.9)
				(max_width 2)
				(curved_edges yes)
				(filter_ratio 0.9)
				(enabled yes)
				(allow_two_segments yes)
				(prefer_zone_connections yes)
			)
		)
		(pad "42" smd rect
			(at 1 1.31 270)
			(size 0.3 1.5)
			(layers "B.Cu" "B.Mask" "B.Paste")
			(net 918 "unconnected-(J5-SMB_DATA-Pad42)")
			(pinfunction "SMB_DATA")
			(pintype "bidirectional+no_connect")
			(teardrops
				(best_length_ratio 0.2)
				(max_length 1)
				(best_width_ratio 0.9)
				(max_width 2)
				(curved_edges yes)
				(filter_ratio 0.9)
				(enabled yes)
				(allow_two_segments yes)
				(prefer_zone_connections yes)
			)
		)
		(pad "43" smd rect
			(at 1.25 3.95 270)
			(size 0.3 1.5)
			(layers "B.Cu" "B.Mask" "B.Paste")
			(net 262 "/Com Express 7 Interfaces/PCIe_{B2Bx4}.RX0-")
			(pinfunction "PER0_P")
			(pintype "output")
			(teardrops
				(best_length_ratio 0.2)
				(max_length 1)
				(best_width_ratio 0.9)
				(max_width 2)
				(curved_edges yes)
				(filter_ratio 0.9)
				(enabled yes)
				(allow_two_segments yes)
				(prefer_zone_connections yes)
			)
		)
		(pad "44" smd rect
			(at 1.5 1.31 270)
			(size 0.3 1.5)
			(layers "B.Cu" "B.Mask" "B.Paste")
			(net 919 "unconnected-(J5-ALERT-Pad44)")
			(pinfunction "ALERT")
			(pintype "output+no_connect")
			(teardrops
				(best_length_ratio 0.2)
				(max_length 1)
				(best_width_ratio 0.9)
				(max_width 2)
				(curved_edges yes)
				(filter_ratio 0.9)
				(enabled yes)
				(allow_two_segments yes)
				(prefer_zone_connections yes)
			)
		)
		(pad "45" smd rect
			(at 1.75 3.95 270)
			(size 0.3 1.5)
			(layers "B.Cu" "B.Mask" "B.Paste")
			(net 1 "GND")
			(pinfunction "GND")
			(pintype "passive")
			(teardrops
				(best_length_ratio 0.2)
				(max_length 1)
				(best_width_ratio 0.9)
				(max_width 2)
				(curved_edges yes)
				(filter_ratio 0.9)
				(enabled yes)
				(allow_two_segments yes)
				(prefer_zone_connections yes)
			)
		)
		(pad "46" smd rect
			(at 2 1.31 270)
			(size 0.3 1.5)
			(layers "B.Cu" "B.Mask" "B.Paste")
			(net 920 "unconnected-(J5-NC-Pad46)")
			(pinfunction "NC")
			(pintype "no_connect")
			(teardrops
				(best_length_ratio 0.2)
				(max_length 1)
				(best_width_ratio 0.9)
				(max_width 2)
				(curved_edges yes)
				(filter_ratio 0.9)
				(enabled yes)
				(allow_two_segments yes)
				(prefer_zone_connections yes)
			)
		)
		(pad "47" smd rect
			(at 2.25 3.95 270)
			(size 0.3 1.5)
			(layers "B.Cu" "B.Mask" "B.Paste")
			(net 269 "/Com Express 7 Interfaces/PCIe_{B2Bx4}.TX0+")
			(pinfunction "PET0_N")
			(pintype "input")
			(teardrops
				(best_length_ratio 0.2)
				(max_length 1)
				(best_width_ratio 0.9)
				(max_width 2)
				(curved_edges yes)
				(filter_ratio 0.9)
				(enabled yes)
				(allow_two_segments yes)
				(prefer_zone_connections yes)
			)
		)
		(pad "48" smd rect
			(at 2.5 1.31 270)
			(size 0.3 1.5)
			(layers "B.Cu" "B.Mask" "B.Paste")
			(net 921 "unconnected-(J5-NC-Pad48)")
			(pinfunction "NC")
			(pintype "no_connect")
			(teardrops
				(best_length_ratio 0.2)
				(max_length 1)
				(best_width_ratio 0.9)
				(max_width 2)
				(curved_edges yes)
				(filter_ratio 0.9)
				(enabled yes)
				(allow_two_segments yes)
				(prefer_zone_connections yes)
			)
		)
		(pad "49" smd rect
			(at 2.75 3.95 270)
			(size 0.3 1.5)
			(layers "B.Cu" "B.Mask" "B.Paste")
			(net 267 "/Com Express 7 Interfaces/PCIe_{B2Bx4}.TX0-")
			(pinfunction "PET0_P")
			(pintype "input")
			(teardrops
				(best_length_ratio 0.2)
				(max_length 1)
				(best_width_ratio 0.9)
				(max_width 2)
				(curved_edges yes)
				(filter_ratio 0.9)
				(enabled yes)
				(allow_two_segments yes)
				(prefer_zone_connections yes)
			)
		)
		(pad "50" smd rect
			(at 3 1.31 270)
			(size 0.3 1.5)
			(layers "B.Cu" "B.Mask" "B.Paste")
			(net 228 "/M.2 key M #1/~{PERST_D}")
			(pinfunction "~{PERST}")
			(pintype "input")
			(teardrops
				(best_length_ratio 0.2)
				(max_length 1)
				(best_width_ratio 0.9)
				(max_width 2)
				(curved_edges yes)
				(filter_ratio 0.9)
				(enabled yes)
				(allow_two_segments yes)
				(prefer_zone_connections yes)
			)
		)
		(pad "51" smd rect
			(at 3.25 3.95 270)
			(size 0.3 1.5)
			(layers "B.Cu" "B.Mask" "B.Paste")
			(net 1 "GND")
			(pinfunction "GND")
			(pintype "passive")
			(teardrops
				(best_length_ratio 0.2)
				(max_length 1)
				(best_width_ratio 0.9)
				(max_width 2)
				(curved_edges yes)
				(filter_ratio 0.9)
				(enabled yes)
				(allow_two_segments yes)
				(prefer_zone_connections yes)
			)
		)
		(pad "52" smd rect
			(at 3.5 1.31 270)
			(size 0.3 1.5)
			(layers "B.Cu" "B.Mask" "B.Paste")
			(net 529 "/M.2 key M #1/~{CLKREQ}")
			(pinfunction "~{CLKREQ}")
			(pintype "output")
			(teardrops
				(best_length_ratio 0.2)
				(max_length 1)
				(best_width_ratio 0.9)
				(max_width 2)
				(curved_edges yes)
				(filter_ratio 0.9)
				(enabled yes)
				(allow_two_segments yes)
				(prefer_zone_connections yes)
			)
		)
		(pad "53" smd rect
			(at 3.75 3.95 270)
			(size 0.3 1.5)
			(layers "B.Cu" "B.Mask" "B.Paste")
			(net 229 "/M.2 key M #1/PCIE_{REF}.CK-")
			(pinfunction "REFCLK_N")
			(pintype "input")
			(teardrops
				(best_length_ratio 0.2)
				(max_length 1)
				(best_width_ratio 0.9)
				(max_width 2)
				(curved_edges yes)
				(filter_ratio 0.9)
				(enabled yes)
				(allow_two_segments yes)
				(prefer_zone_connections yes)
			)
		)
		(pad "54" smd rect
			(at 4 1.31 270)
			(size 0.3 1.5)
			(layers "B.Cu" "B.Mask" "B.Paste")
			(net 922 "unconnected-(J5-~{PEWAKE}-Pad54)")
			(pinfunction "~{PEWAKE}")
			(pintype "input+no_connect")
			(teardrops
				(best_length_ratio 0.2)
				(max_length 1)
				(best_width_ratio 0.9)
				(max_width 2)
				(curved_edges yes)
				(filter_ratio 0.9)
				(enabled yes)
				(allow_two_segments yes)
				(prefer_zone_connections yes)
			)
		)
		(pad "55" smd rect
			(at 4.25 3.95 270)
			(size 0.3 1.5)
			(layers "B.Cu" "B.Mask" "B.Paste")
			(net 231 "/M.2 key M #1/PCIE_{REF}.CK+")
			(pinfunction "REFCLK_P")
			(pintype "input")
			(teardrops
				(best_length_ratio 0.2)
				(max_length 1)
				(best_width_ratio 0.9)
				(max_width 2)
				(curved_edges yes)
				(filter_ratio 0.9)
				(enabled yes)
				(allow_two_segments yes)
				(prefer_zone_connections yes)
			)
		)
		(pad "56" smd rect
			(at 4.5 1.31 270)
			(size 0.3 1.5)
			(layers "B.Cu" "B.Mask" "B.Paste")
			(net 923 "unconnected-(J5-NC-Pad56)")
			(pinfunction "NC")
			(pintype "no_connect")
			(teardrops
				(best_length_ratio 0.2)
				(max_length 1)
				(best_width_ratio 0.9)
				(max_width 2)
				(curved_edges yes)
				(filter_ratio 0.9)
				(enabled yes)
				(allow_two_segments yes)
				(prefer_zone_connections yes)
			)
		)
		(pad "57" smd rect
			(at 4.75 3.95 270)
			(size 0.3 1.5)
			(layers "B.Cu" "B.Mask" "B.Paste")
			(net 1 "GND")
			(pinfunction "GND")
			(pintype "passive")
			(teardrops
				(best_length_ratio 0.2)
				(max_length 1)
				(best_width_ratio 0.9)
				(max_width 2)
				(curved_edges yes)
				(filter_ratio 0.9)
				(enabled yes)
				(allow_two_segments yes)
				(prefer_zone_connections yes)
			)
		)
		(pad "58" smd rect
			(at 5 1.31 270)
			(size 0.3 1.5)
			(layers "B.Cu" "B.Mask" "B.Paste")
			(net 924 "unconnected-(J5-NC-Pad58)")
			(pinfunction "NC")
			(pintype "no_connect")
			(teardrops
				(best_length_ratio 0.2)
				(max_length 1)
				(best_width_ratio 0.9)
				(max_width 2)
				(curved_edges yes)
				(filter_ratio 0.9)
				(enabled yes)
				(allow_two_segments yes)
				(prefer_zone_connections yes)
			)
		)
		(pad "67" smd rect
			(at 7.25 3.95 270)
			(size 0.3 1.5)
			(layers "B.Cu" "B.Mask" "B.Paste")
			(net 925 "unconnected-(J5-NC-Pad67)")
			(pinfunction "NC")
			(pintype "no_connect")
			(teardrops
				(best_length_ratio 0.2)
				(max_length 1)
				(best_width_ratio 0.9)
				(max_width 2)
				(curved_edges yes)
				(filter_ratio 0.9)
				(enabled yes)
				(allow_two_segments yes)
				(prefer_zone_connections yes)
			)
		)
		(pad "68" smd rect
			(at 7.5 1.31 270)
			(size 0.3 1.5)
			(layers "B.Cu" "B.Mask" "B.Paste")
			(net 926 "Net-(J5-SUSCLK)")
			(pinfunction "SUSCLK")
			(pintype "input")
			(teardrops
				(best_length_ratio 0.2)
				(max_length 1)
				(best_width_ratio 0.9)
				(max_width 2)
				(curved_edges yes)
				(filter_ratio 0.9)
				(enabled yes)
				(allow_two_segments yes)
				(prefer_zone_connections yes)
			)
		)
		(pad "69" smd rect
			(at 7.75 3.95 270)
			(size 0.3 1.5)
			(layers "B.Cu" "B.Mask" "B.Paste")
			(net 927 "unconnected-(J5-NC-Pad69)")
			(pinfunction "NC")
			(pintype "no_connect")
			(teardrops
				(best_length_ratio 0.2)
				(max_length 1)
				(best_width_ratio 0.9)
				(max_width 2)
				(curved_edges yes)
				(filter_ratio 0.9)
				(enabled yes)
				(allow_two_segments yes)
				(prefer_zone_connections yes)
			)
		)
		(pad "70" smd rect
			(at 8 1.31 270)
			(size 0.3 1.5)
			(layers "B.Cu" "B.Mask" "B.Paste")
			(net 969 "/M.2 key M #1/M2_3V3")
			(pinfunction "3V3")
			(pintype "passive")
			(teardrops
				(best_length_ratio 0.2)
				(max_length 1)
				(best_width_ratio 0.9)
				(max_width 2)
				(curved_edges yes)
				(filter_ratio 0.9)
				(enabled yes)
				(allow_two_segments yes)
				(prefer_zone_connections yes)
			)
		)
		(pad "71" smd rect
			(at 8.25 3.95 270)
			(size 0.3 1.5)
			(layers "B.Cu" "B.Mask" "B.Paste")
			(net 1 "GND")
			(pinfunction "GND")
			(pintype "passive")
			(teardrops
				(best_length_ratio 0.2)
				(max_length 1)
				(best_width_ratio 0.9)
				(max_width 2)
				(curved_edges yes)
				(filter_ratio 0.9)
				(enabled yes)
				(allow_two_segments yes)
				(prefer_zone_connections yes)
			)
		)
		(pad "72" smd rect
			(at 8.5 1.31 270)
			(size 0.3 1.5)
			(layers "B.Cu" "B.Mask" "B.Paste")
			(net 969 "/M.2 key M #1/M2_3V3")
			(pinfunction "3V3")
			(pintype "passive")
			(teardrops
				(best_length_ratio 0.2)
				(max_length 1)
				(best_width_ratio 0.9)
				(max_width 2)
				(curved_edges yes)
				(filter_ratio 0.9)
				(enabled yes)
				(allow_two_segments yes)
				(prefer_zone_connections yes)
			)
		)
		(pad "73" smd rect
			(at 8.75 3.95 270)
			(size 0.3 1.5)
			(layers "B.Cu" "B.Mask" "B.Paste")
			(net 1 "GND")
			(pinfunction "GND")
			(pintype "passive")
			(teardrops
				(best_length_ratio 0.2)
				(max_length 1)
				(best_width_ratio 0.9)
				(max_width 2)
				(curved_edges yes)
				(filter_ratio 0.9)
				(enabled yes)
				(allow_two_segments yes)
				(prefer_zone_connections yes)
			)
		)
		(pad "74" smd rect
			(at 9 1.31 270)
			(size 0.3 1.5)
			(layers "B.Cu" "B.Mask" "B.Paste")
			(net 969 "/M.2 key M #1/M2_3V3")
			(pinfunction "3V3")
			(pintype "passive")
			(teardrops
				(best_length_ratio 0.2)
				(max_length 1)
				(best_width_ratio 0.9)
				(max_width 2)
				(curved_edges yes)
				(filter_ratio 0.9)
				(enabled yes)
				(allow_two_segments yes)
				(prefer_zone_connections yes)
			)
		)
		(pad "75" smd rect
			(at 9.25 3.95 270)
			(size 0.3 1.5)
			(layers "B.Cu" "B.Mask" "B.Paste")
			(net 1 "GND")
			(pinfunction "GND")
			(pintype "passive")
			(teardrops
				(best_length_ratio 0.2)
				(max_length 1)
				(best_width_ratio 0.9)
				(max_width 2)
				(curved_edges yes)
				(filter_ratio 0.9)
				(enabled yes)
				(allow_two_segments yes)
				(prefer_zone_connections yes)
			)
		)
		(pad "SH" smd rect
			(at -11.585 -2.57 270)
			(size 1.2 2.6)
			(layers "B.Cu" "B.Mask" "B.Paste")
			(net 1 "GND")
			(pinfunction "SH")
			(pintype "passive")
			(solder_mask_margin 0.102)
			(teardrops
				(best_length_ratio 0.2)
				(max_length 1)
				(best_width_ratio 0.9)
				(max_width 2)
				(curved_edges yes)
				(filter_ratio 0.9)
				(enabled yes)
				(allow_two_segments yes)
				(prefer_zone_connections yes)
			)
		)
		(pad "SH" smd rect
			(at 11.585 -2.57 270)
			(size 1.2 2.6)
			(layers "B.Cu" "B.Mask" "B.Paste")
			(net 1 "GND")
			(pinfunction "SH")
			(pintype "passive")
			(solder_mask_margin 0.102)
			(teardrops
				(best_length_ratio 0.2)
				(max_length 1)
				(best_width_ratio 0.9)
				(max_width 2)
				(curved_edges yes)
				(filter_ratio 0.9)
				(enabled yes)
				(allow_two_segments yes)
				(prefer_zone_connections yes)
			)
		)
	)
)
